(kicad_pcb
	(version 20260206)
	(generator "pcbnew")
	(generator_version "10.0")
	(general
		(thickness 1.6)
		(legacy_teardrops no)
	)
	(paper "A4")
	(title_block
		(title "Bryce Canyon_SCC_16316-1_OCP.brd")
		(comment 1 "Bryce Canyon / footprints 600-608 of 1561")
	)
	(layers
		(0 "F.Cu" signal "TOP")
		(4 "In1.Cu" signal "L2GND")
		(6 "In2.Cu" signal "L3")
		(8 "In3.Cu" signal "L4VCC")
		(10 "In4.Cu" signal "L5VCC")
		(12 "In5.Cu" signal "L6")
		(14 "In6.Cu" signal "L7GND")
		(2 "B.Cu" signal "BOTTOM")
		(9 "F.Adhes" user "F.Adhesive")
		(11 "B.Adhes" user "B.Adhesive")
		(13 "F.Paste" user "Package Geometry/Pastemask Top")
		(15 "B.Paste" user "Package Geometry/Pastemask Bottom")
		(5 "F.SilkS" user "Ref Des/Silkscreen Top")
		(7 "B.SilkS" user "Ref Des/Silkscreen Bottom")
		(1 "F.Mask" user "Board Geometry/Soldermask Top")
		(3 "B.Mask" user "Board Geometry/Soldermask Bottom")
		(17 "Dwgs.User" user "User.Drawings")
		(19 "Cmts.User" user "User.Comments")
		(21 "Eco1.User" user "User.Eco1")
		(23 "Eco2.User" user "User.Eco2")
		(25 "Edge.Cuts" user "Board Geometry/Outline")
		(27 "Margin" user)
		(31 "F.CrtYd" user "Package Geometry/Place Bound Top")
		(29 "B.CrtYd" user "Package Geometry/Place Bound Bottom")
		(35 "F.Fab" user "Ref Des/Assembly Top")
		(33 "B.Fab" user "Ref Des/Assembly Bottom")
	)
	(footprint ""
		(layer "F.Cu")
		(at 181.8386 -118.8466 90)
		(property "Reference" "C688"
			(at 0 0 90)
			(layer "F.SilkS")
			(hide yes)
			(effects
				(font
					(size 1.27 1.27)
				)
			)
		)
		(property "Value" "SC10U6D3V5KX-4GP"
			(at -0.0762 -6.1214 90)
			(unlocked yes)
			(layer "F.Fab")
			(hide yes)
			(effects
				(font
					(size 1.016 1.016)
					(thickness 0.1524)
				)
			)
		)
		(property "Device Type" "C805H58"
			(at -0.0762 -8.1534 90)
			(unlocked yes)
			(layer "F.Fab")
			(hide yes)
			(effects
				(font
					(size 1.016 1.016)
					(thickness 0.1524)
				)
			)
		)
		(duplicate_pad_numbers_are_jumpers no)
		(fp_line
			(start 0.635 0)
			(end -0.635 0)
			(stroke
				(width 0.508)
				(type default)
			)
			(layer "F.SilkS")
		)
		(fp_rect
			(start -0.9652 1.778)
			(end 0.9652 -1.778)
			(stroke
				(width 0)
				(type default)
			)
			(fill no)
			(layer "F.CrtYd")
		)
		(fp_poly
			(pts
				(xy -0.9652 -1.778) (xy 0.9652 -1.778) (xy 0.9652 1.778) (xy -0.9652 1.778)
			)
			(stroke
				(width 0)
				(type default)
			)
			(fill no)
			(layer "F.Fab")
		)
		(pad "1" smd rect
			(at 0 -0.9652 90)
			(size 1.397 1.143)
			(layers "F.Cu" "F.Mask" "F.Paste")
			(net "P1V8_E_OUT")
		)
		(pad "2" smd rect
			(at 0 0.9652 90)
			(size 1.397 1.143)
			(layers "F.Cu" "F.Mask" "F.Paste")
			(net "GND")
		)
	)
	(footprint ""
		(layer "F.Cu")
		(at 45.1612 -27.94 90)
		(property "Reference" "R399"
			(at 0 0 90)
			(layer "F.SilkS")
			(hide yes)
			(effects
				(font
					(size 1.27 1.27)
				)
			)
		)
		(property "Value" "8K06R2F-GP"
			(at 0.064008 -3.993896 90)
			(unlocked yes)
			(layer "F.Fab")
			(hide yes)
			(effects
				(font
					(size 1.016 1.016)
					(thickness 0.1524)
				)
			)
		)
		(property "Device Type" "R402H16"
			(at 0.064008 -5.517896 90)
			(unlocked yes)
			(layer "F.Fab")
			(hide yes)
			(effects
				(font
					(size 1.016 1.016)
					(thickness 0.1524)
				)
			)
		)
		(duplicate_pad_numbers_are_jumpers no)
		(fp_line
			(start 0.508 -0.9398)
			(end -0.508 -0.9398)
			(stroke
				(width 0.1524)
				(type default)
			)
			(layer "F.SilkS")
		)
		(fp_line
			(start -0.508 -0.9398)
			(end -0.508 0.9398)
			(stroke
				(width 0.1524)
				(type default)
			)
			(layer "F.SilkS")
		)
		(fp_rect
			(start -0.508 0.9398)
			(end 0.508 -0.9398)
			(stroke
				(width 0)
				(type default)
			)
			(fill no)
			(layer "F.CrtYd")
		)
		(fp_rect
			(start -0.508 0.9398)
			(end 0.508 -0.9398)
			(stroke
				(width 0)
				(type default)
			)
			(fill no)
			(layer "F.Fab")
		)
		(pad "1" smd custom
			(at 0 -0.4445 90)
			(size 0.1397 0.1397)
			(layers "F.Cu" "F.Mask" "F.Paste")
			(net "P0V9_REFIN")
			(options
				(clearance outline)
				(anchor circle)
			)
			(primitives
				(gr_poly
					(pts
						(arc
							(start -0.1778 -0.2794)
							(mid -0.249642 -0.249642)
							(end -0.2794 -0.1778)
						)
						(arc
							(start -0.2794 0.1778)
							(mid -0.249642 0.249642)
							(end -0.1778 0.2794)
						)
						(arc
							(start 0.1778 0.2794)
							(mid 0.249642 0.249642)
							(end 0.2794 0.1778)
						)
						(arc
							(start 0.2794 -0.1778)
							(mid 0.249642 -0.249642)
							(end 0.1778 -0.2794)
						)
					)
					(width 0)
					(fill yes)
				)
			)
		)
		(pad "2" smd custom
			(at 0 0.4445 90)
			(size 0.1397 0.1397)
			(layers "F.Cu" "F.Mask" "F.Paste")
			(net "P0V9_GSNS")
			(options
				(clearance outline)
				(anchor circle)
			)
			(primitives
				(gr_poly
					(pts
						(arc
							(start -0.1778 -0.2794)
							(mid -0.249642 -0.249642)
							(end -0.2794 -0.1778)
						)
						(arc
							(start -0.2794 0.1778)
							(mid -0.249642 0.249642)
							(end -0.1778 0.2794)
						)
						(arc
							(start 0.1778 0.2794)
							(mid 0.249642 0.249642)
							(end 0.2794 0.1778)
						)
						(arc
							(start 0.2794 -0.1778)
							(mid 0.249642 -0.249642)
							(end 0.1778 -0.2794)
						)
					)
					(width 0)
					(fill yes)
				)
			)
		)
	)
	(footprint ""
		(layer "F.Cu")
		(at 7.366 -82.042 90)
		(property "Reference" "R335"
			(at 0 0 90)
			(layer "F.SilkS")
			(hide yes)
			(effects
				(font
					(size 1.27 1.27)
				)
			)
		)
		(property "Value" "4K7R2F-GP"
			(at 0.064008 -3.993896 90)
			(unlocked yes)
			(layer "F.Fab")
			(hide yes)
			(effects
				(font
					(size 1.016 1.016)
					(thickness 0.1524)
				)
			)
		)
		(property "Device Type" "R402H16"
			(at 0.064008 -5.517896 90)
			(unlocked yes)
			(layer "F.Fab")
			(hide yes)
			(effects
				(font
					(size 1.016 1.016)
					(thickness 0.1524)
				)
			)
		)
		(duplicate_pad_numbers_are_jumpers no)
		(fp_line
			(start 0.508 -0.9398)
			(end -0.508 -0.9398)
			(stroke
				(width 0.1524)
				(type default)
			)
			(layer "F.SilkS")
		)
		(fp_line
			(start -0.508 -0.9398)
			(end -0.508 0.9398)
			(stroke
				(width 0.1524)
				(type default)
			)
			(layer "F.SilkS")
		)
		(fp_rect
			(start -0.508 0.9398)
			(end 0.508 -0.9398)
			(stroke
				(width 0)
				(type default)
			)
			(fill no)
			(layer "F.CrtYd")
		)
		(fp_rect
			(start -0.508 0.9398)
			(end 0.508 -0.9398)
			(stroke
				(width 0)
				(type default)
			)
			(fill no)
			(layer "F.Fab")
		)
		(pad "1" smd custom
			(at 0 -0.4445 90)
			(size 0.1397 0.1397)
			(layers "F.Cu" "F.Mask" "F.Paste")
			(net "P3V3")
			(options
				(clearance outline)
				(anchor circle)
			)
			(primitives
				(gr_poly
					(pts
						(arc
							(start -0.1778 -0.2794)
							(mid -0.249642 -0.249642)
							(end -0.2794 -0.1778)
						)
						(arc
							(start -0.2794 0.1778)
							(mid -0.249642 0.249642)
							(end -0.1778 0.2794)
						)
						(arc
							(start 0.1778 0.2794)
							(mid 0.249642 0.249642)
							(end 0.2794 0.1778)
						)
						(arc
							(start 0.2794 -0.1778)
							(mid 0.249642 -0.249642)
							(end 0.1778 -0.2794)
						)
					)
					(width 0)
					(fill yes)
				)
			)
		)
		(pad "2" smd custom
			(at 0 0.4445 90)
			(size 0.1397 0.1397)
			(layers "F.Cu" "F.Mask" "F.Paste")
			(net "EXP_EEPROM_A0")
			(options
				(clearance outline)
				(anchor circle)
			)
			(primitives
				(gr_poly
					(pts
						(arc
							(start -0.1778 -0.2794)
							(mid -0.249642 -0.249642)
							(end -0.2794 -0.1778)
						)
						(arc
							(start -0.2794 0.1778)
							(mid -0.249642 0.249642)
							(end -0.1778 0.2794)
						)
						(arc
							(start 0.1778 0.2794)
							(mid 0.249642 0.249642)
							(end 0.2794 0.1778)
						)
						(arc
							(start 0.2794 -0.1778)
							(mid 0.249642 -0.249642)
							(end 0.1778 -0.2794)
						)
					)
					(width 0)
					(fill yes)
				)
			)
		)
	)
	(footprint ""
		(layer "F.Cu")
		(at 7.366 -79.756 -90)
		(property "Reference" "R345"
			(at 0 0 270)
			(layer "F.SilkS")
			(hide yes)
			(effects
				(font
					(size 1.27 1.27)
				)
			)
		)
		(property "Value" "4K7R2F-GP"
			(at 0.064008 -3.993896 270)
			(unlocked yes)
			(layer "F.Fab")
			(hide yes)
			(effects
				(font
					(size 1.016 1.016)
					(thickness 0.1524)
				)
			)
		)
		(property "Device Type" "R402H16"
			(at 0.064008 -5.517896 270)
			(unlocked yes)
			(layer "F.Fab")
			(hide yes)
			(effects
				(font
					(size 1.016 1.016)
					(thickness 0.1524)
				)
			)
		)
		(duplicate_pad_numbers_are_jumpers no)
		(fp_line
			(start -0.508 -0.9398)
			(end -0.508 0.9398)
			(stroke
				(width 0.1524)
				(type default)
			)
			(layer "F.SilkS")
		)
		(fp_line
			(start 0.508 -0.9398)
			(end -0.508 -0.9398)
			(stroke
				(width 0.1524)
				(type default)
			)
			(layer "F.SilkS")
		)
		(fp_rect
			(start -0.508 0.9398)
			(end 0.508 -0.9398)
			(stroke
				(width 0)
				(type default)
			)
			(fill no)
			(layer "F.CrtYd")
		)
		(fp_rect
			(start -0.508 0.9398)
			(end 0.508 -0.9398)
			(stroke
				(width 0)
				(type default)
			)
			(fill no)
			(layer "F.Fab")
		)
		(pad "1" smd custom
			(at 0 -0.4445 270)
			(size 0.1397 0.1397)
			(layers "F.Cu" "F.Mask" "F.Paste")
			(net "EXP_EEPROM_A1")
			(options
				(clearance outline)
				(anchor circle)
			)
			(primitives
				(gr_poly
					(pts
						(arc
							(start -0.1778 -0.2794)
							(mid -0.249642 -0.249642)
							(end -0.2794 -0.1778)
						)
						(arc
							(start -0.2794 0.1778)
							(mid -0.249642 0.249642)
							(end -0.1778 0.2794)
						)
						(arc
							(start 0.1778 0.2794)
							(mid 0.249642 0.249642)
							(end 0.2794 0.1778)
						)
						(arc
							(start 0.2794 -0.1778)
							(mid 0.249642 -0.249642)
							(end 0.1778 -0.2794)
						)
					)
					(width 0)
					(fill yes)
				)
			)
		)
		(pad "2" smd custom
			(at 0 0.4445 270)
			(size 0.1397 0.1397)
			(layers "F.Cu" "F.Mask" "F.Paste")
			(net "GND")
			(options
				(clearance outline)
				(anchor circle)
			)
			(primitives
				(gr_poly
					(pts
						(arc
							(start -0.1778 -0.2794)
							(mid -0.249642 -0.249642)
							(end -0.2794 -0.1778)
						)
						(arc
							(start -0.2794 0.1778)
							(mid -0.249642 0.249642)
							(end -0.1778 0.2794)
						)
						(arc
							(start 0.1778 0.2794)
							(mid 0.249642 0.249642)
							(end 0.2794 0.1778)
						)
						(arc
							(start 0.2794 -0.1778)
							(mid 0.249642 -0.249642)
							(end 0.1778 -0.2794)
						)
					)
					(width 0)
					(fill yes)
				)
			)
		)
	)
	(footprint ""
		(layer "F.Cu")
		(at 125.2728 -88.3158)
		(property "Reference" "TP44"
			(at 0 0 0)
			(layer "F.SilkS")
			(hide yes)
			(effects
				(font
					(size 1.27 1.27)
				)
			)
		)
		(property "Value" "TPAD28-2-GP"
			(at -0.0127 -1.6637 0)
			(unlocked yes)
			(layer "F.Fab")
			(hide yes)
			(effects
				(font
					(size 1.016 1.016)
					(thickness 0.1524)
				)
			)
		)
		(property "Device Type" "TPAD28"
			(at -0.0127 -3.1877 0)
			(unlocked yes)
			(layer "F.Fab")
			(hide yes)
			(effects
				(font
					(size 1.016 1.016)
					(thickness 0.1524)
				)
			)
		)
		(duplicate_pad_numbers_are_jumpers no)
		(fp_poly
			(pts
				(arc
					(start 0.3556 0)
					(mid -0.3556 0)
					(end 0.3556 0)
				)
			)
			(stroke
				(width 0)
				(type default)
			)
			(fill no)
			(layer "F.CrtYd")
		)
		(fp_poly
			(pts
				(arc
					(start 0.6096 0)
					(mid -0.6096 0)
					(end 0.6096 0)
				)
			)
			(stroke
				(width 0)
				(type default)
			)
			(fill no)
			(layer "F.Fab")
		)
		(pad "1" smd circle
			(at 0 0)
			(size 0.7112 0.7112)
			(layers "F.Cu" "F.Mask" "F.Paste")
			(net "PHY_CLK")
		)
	)
	(footprint ""
		(layer "F.Cu")
		(at 190.2968 -32.0675 -90)
		(property "Reference" "TP76"
			(at 0 0 270)
			(layer "F.SilkS")
			(hide yes)
			(effects
				(font
					(size 1.27 1.27)
				)
			)
		)
		(property "Value" "TPAD28-2-GP"
			(at -0.0127 -1.6637 270)
			(unlocked yes)
			(layer "F.Fab")
			(hide yes)
			(effects
				(font
					(size 1.016 1.016)
					(thickness 0.1524)
				)
			)
		)
		(property "Device Type" "TPAD28"
			(at -0.0127 -3.1877 270)
			(unlocked yes)
			(layer "F.Fab")
			(hide yes)
			(effects
				(font
					(size 1.016 1.016)
					(thickness 0.1524)
				)
			)
		)
		(duplicate_pad_numbers_are_jumpers no)
		(fp_poly
			(pts
				(arc
					(start 0 -0.3556)
					(mid 0 0.3556)
					(end 0 -0.3556)
				)
			)
			(stroke
				(width 0)
				(type default)
			)
			(fill no)
			(layer "F.CrtYd")
		)
		(fp_poly
			(pts
				(arc
					(start 0 -0.6096)
					(mid 0 0.6096)
					(end 0 -0.6096)
				)
			)
			(stroke
				(width 0)
				(type default)
			)
			(fill no)
			(layer "F.Fab")
		)
		(pad "1" smd circle
			(at 0 0 270)
			(size 0.7112 0.7112)
			(layers "F.Cu" "F.Mask" "F.Paste")
			(net "IOC_GPIO_23")
		)
	)
	(footprint ""
		(layer "F.Cu")
		(at 173.4058 -56.7182)
		(property "Reference" "TP138"
			(at 0 0 0)
			(layer "F.SilkS")
			(hide yes)
			(effects
				(font
					(size 1.27 1.27)
				)
			)
		)
		(property "Value" "TPAD28-2-GP"
			(at -0.0127 -1.6637 0)
			(unlocked yes)
			(layer "F.Fab")
			(hide yes)
			(effects
				(font
					(size 1.016 1.016)
					(thickness 0.1524)
				)
			)
		)
		(property "Device Type" "TPAD28"
			(at -0.0127 -3.1877 0)
			(unlocked yes)
			(layer "F.Fab")
			(hide yes)
			(effects
				(font
					(size 1.016 1.016)
					(thickness 0.1524)
				)
			)
		)
		(duplicate_pad_numbers_are_jumpers no)
		(fp_poly
			(pts
				(arc
					(start 0.3556 0)
					(mid -0.3556 0)
					(end 0.3556 0)
				)
			)
			(stroke
				(width 0)
				(type default)
			)
			(fill no)
			(layer "F.CrtYd")
		)
		(fp_poly
			(pts
				(arc
					(start 0.6096 0)
					(mid -0.6096 0)
					(end 0.6096 0)
				)
			)
			(stroke
				(width 0)
				(type default)
			)
			(fill no)
			(layer "F.Fab")
		)
		(pad "1" smd circle
			(at 0 0)
			(size 0.7112 0.7112)
			(layers "F.Cu" "F.Mask" "F.Paste")
			(net "IOC_TRST_N")
		)
	)
	(footprint ""
		(layer "F.Cu")
		(at 54.6862 -72.5678)
		(property "Reference" "R473"
			(at 0 0 0)
			(layer "F.SilkS")
			(hide yes)
			(effects
				(font
					(size 1.27 1.27)
				)
			)
		)
		(property "Value" "0R2J-2-GP"
			(at 0.064008 -3.993896 0)
			(unlocked yes)
			(layer "F.Fab")
			(hide yes)
			(effects
				(font
					(size 1.016 1.016)
					(thickness 0.1524)
				)
			)
		)
		(property "Device Type" "R402H16"
			(at 0.064008 -5.517896 0)
			(unlocked yes)
			(layer "F.Fab")
			(hide yes)
			(effects
				(font
					(size 1.016 1.016)
					(thickness 0.1524)
				)
			)
		)
		(duplicate_pad_numbers_are_jumpers no)
		(fp_line
			(start -0.508 -0.9398)
			(end -0.508 0.9398)
			(stroke
				(width 0.1524)
				(type default)
			)
			(layer "F.SilkS")
		)
		(fp_line
			(start 0.508 -0.9398)
			(end -0.508 -0.9398)
			(stroke
				(width 0.1524)
				(type default)
			)
			(layer "F.SilkS")
		)
		(fp_rect
			(start -0.508 0.9398)
			(end 0.508 -0.9398)
			(stroke
				(width 0)
				(type default)
			)
			(fill no)
			(layer "F.CrtYd")
		)
		(fp_rect
			(start -0.508 0.9398)
			(end 0.508 -0.9398)
			(stroke
				(width 0)
				(type default)
			)
			(fill no)
			(layer "F.Fab")
		)
		(pad "1" smd custom
			(at 0 -0.4445)
			(size 0.1397 0.1397)
			(layers "F.Cu" "F.Mask" "F.Paste")
			(net "LS_EN_U41")
			(options
				(clearance outline)
				(anchor circle)
			)
			(primitives
				(gr_poly
					(pts
						(arc
							(start -0.1778 -0.2794)
							(mid -0.249642 -0.249642)
							(end -0.2794 -0.1778)
						)
						(arc
							(start -0.2794 0.1778)
							(mid -0.249642 0.249642)
							(end -0.1778 0.2794)
						)
						(arc
							(start 0.1778 0.2794)
							(mid 0.249642 0.249642)
							(end 0.2794 0.1778)
						)
						(arc
							(start 0.2794 -0.1778)
							(mid 0.249642 -0.249642)
							(end 0.1778 -0.2794)
						)
					)
					(width 0)
					(fill yes)
				)
			)
		)
		(pad "2" smd custom
			(at 0 0.4445)
			(size 0.1397 0.1397)
			(layers "F.Cu" "F.Mask" "F.Paste")
			(net "VREF7")
			(options
				(clearance outline)
				(anchor circle)
			)
			(primitives
				(gr_poly
					(pts
						(arc
							(start -0.1778 -0.2794)
							(mid -0.249642 -0.249642)
							(end -0.2794 -0.1778)
						)
						(arc
							(start -0.2794 0.1778)
							(mid -0.249642 0.249642)
							(end -0.1778 0.2794)
						)
						(arc
							(start 0.1778 0.2794)
							(mid 0.249642 0.249642)
							(end 0.2794 0.1778)
						)
						(arc
							(start 0.2794 -0.1778)
							(mid 0.249642 -0.249642)
							(end 0.1778 -0.2794)
						)
					)
					(width 0)
					(fill yes)
				)
			)
		)
	)
	(footprint ""
		(layer "F.Cu")
		(at 114.6556 -86.995 180)
		(property "Reference" "R147"
			(at 0 0 180)
			(layer "F.SilkS")
			(hide yes)
			(effects
				(font
					(size 1.27 1.27)
				)
			)
		)
		(property "Value" "4K7R2F-GP"
			(at 0.064008 -3.993896 180)
			(unlocked yes)
			(layer "F.Fab")
			(hide yes)
			(effects
				(font
					(size 1.016 1.016)
					(thickness 0.1524)
				)
			)
		)
		(property "Device Type" "R402H16"
			(at 0.064008 -5.517896 180)
			(unlocked yes)
			(layer "F.Fab")
			(hide yes)
			(effects
				(font
					(size 1.016 1.016)
					(thickness 0.1524)
				)
			)
		)
		(duplicate_pad_numbers_are_jumpers no)
		(fp_line
			(start 0.508 -0.9398)
			(end -0.508 -0.9398)
			(stroke
				(width 0.1524)
				(type default)
			)
			(layer "F.SilkS")
		)
		(fp_line
			(start -0.508 -0.9398)
			(end -0.508 0.9398)
			(stroke
				(width 0.1524)
				(type default)
			)
			(layer "F.SilkS")
		)
		(fp_rect
			(start -0.508 0.9398)
			(end 0.508 -0.9398)
			(stroke
				(width 0)
				(type default)
			)
			(fill no)
			(layer "F.CrtYd")
		)
		(fp_rect
			(start -0.508 0.9398)
			(end 0.508 -0.9398)
			(stroke
				(width 0)
				(type default)
			)
			(fill no)
			(layer "F.Fab")
		)
		(pad "1" smd custom
			(at 0 -0.4445 180)
			(size 0.1397 0.1397)
			(layers "F.Cu" "F.Mask" "F.Paste")
			(net "EXP_XM_ADDR_25")
			(options
				(clearance outline)
				(anchor circle)
			)
			(primitives
				(gr_poly
					(pts
						(arc
							(start -0.1778 -0.2794)
							(mid -0.249642 -0.249642)
							(end -0.2794 -0.1778)
						)
						(arc
							(start -0.2794 0.1778)
							(mid -0.249642 0.249642)
							(end -0.1778 0.2794)
						)
						(arc
							(start 0.1778 0.2794)
							(mid 0.249642 0.249642)
							(end 0.2794 0.1778)
						)
						(arc
							(start 0.2794 -0.1778)
							(mid 0.249642 -0.249642)
							(end 0.1778 -0.2794)
						)
					)
					(width 0)
					(fill yes)
				)
			)
		)
		(pad "2" smd custom
			(at 0 0.4445 180)
			(size 0.1397 0.1397)
			(layers "F.Cu" "F.Mask" "F.Paste")
			(net "GND")
			(options
				(clearance outline)
				(anchor circle)
			)
			(primitives
				(gr_poly
					(pts
						(arc
							(start -0.1778 -0.2794)
							(mid -0.249642 -0.249642)
							(end -0.2794 -0.1778)
						)
						(arc
							(start -0.2794 0.1778)
							(mid -0.249642 0.249642)
							(end -0.1778 0.2794)
						)
						(arc
							(start 0.1778 0.2794)
							(mid 0.249642 0.249642)
							(end 0.2794 0.1778)
						)
						(arc
							(start 0.2794 -0.1778)
							(mid 0.249642 -0.249642)
							(end 0.1778 -0.2794)
						)
					)
					(width 0)
					(fill yes)
				)
			)
		)
	)
)
